(kicad_pcb
	(version 20260206)
	(generator "pcbnew")
	(generator_version "10.0")
	(general
		(thickness 1.6)
		(legacy_teardrops no)
	)
	(paper "A4")
	(title_block
		(title "Bryce Canyon_F.DPB_16315-1-OCP.brd")
		(comment 1 "Bryce Canyon / footprints 491-497 of 2223")
	)
	(layers
		(0 "F.Cu" signal "TOP")
		(4 "In1.Cu" signal "L2GND")
		(6 "In2.Cu" signal "L3")
		(8 "In3.Cu" signal "L4GND")
		(10 "In4.Cu" signal "L5")
		(12 "In5.Cu" signal "L6VCC")
		(14 "In6.Cu" signal "L7VCC")
		(16 "In7.Cu" signal "L8")
		(18 "In8.Cu" signal "L9GND")
		(20 "In9.Cu" signal "L10")
		(22 "In10.Cu" signal "L11GND")
		(2 "B.Cu" signal "BOTTOM")
		(9 "F.Adhes" user "F.Adhesive")
		(11 "B.Adhes" user "B.Adhesive")
		(13 "F.Paste" user "Package Geometry/Pastemask Top")
		(15 "B.Paste" user "Package Geometry/Pastemask Bottom")
		(5 "F.SilkS" user "Ref Des/Silkscreen Top")
		(7 "B.SilkS" user "Ref Des/Silkscreen Bottom")
		(1 "F.Mask" user "Board Geometry/Soldermask Top")
		(3 "B.Mask" user "Board Geometry/Soldermask Bottom")
		(17 "Dwgs.User" user "User.Drawings")
		(19 "Cmts.User" user "User.Comments")
		(21 "Eco1.User" user "User.Eco1")
		(23 "Eco2.User" user "User.Eco2")
		(25 "Edge.Cuts" user "Board Geometry/Outline")
		(27 "Margin" user)
		(31 "F.CrtYd" user "Package Geometry/Place Bound Top")
		(29 "B.CrtYd" user "Package Geometry/Place Bound Bottom")
		(35 "F.Fab" user "Ref Des/Assembly Top")
		(33 "B.Fab" user "Ref Des/Assembly Bottom")
	)
	(footprint ""
		(layer "F.Cu")
		(at 368.481102 -275.735542 180)
		(property "Reference" "R305"
			(at 0 0 180)
			(layer "F.SilkS")
			(hide yes)
			(effects
				(font
					(size 1.27 1.27)
				)
			)
		)
		(property "Value" "4K7R2J-2-GP"
			(at 0.064008 -3.993896 180)
			(unlocked yes)
			(layer "F.Fab")
			(hide yes)
			(effects
				(font
					(size 1.016 1.016)
					(thickness 0.1524)
				)
			)
		)
		(property "Device Type" "R402H16"
			(at 0.064008 -5.517896 180)
			(unlocked yes)
			(layer "F.Fab")
			(hide yes)
			(effects
				(font
					(size 1.016 1.016)
					(thickness 0.1524)
				)
			)
		)
		(duplicate_pad_numbers_are_jumpers no)
		(fp_line
			(start 0.508 -0.9398)
			(end -0.508 -0.9398)
			(stroke
				(width 0.1524)
				(type default)
			)
			(layer "F.SilkS")
		)
		(fp_line
			(start -0.508 -0.9398)
			(end -0.508 0.9398)
			(stroke
				(width 0.1524)
				(type default)
			)
			(layer "F.SilkS")
		)
		(fp_rect
			(start -0.508 0.9398)
			(end 0.508 -0.9398)
			(stroke
				(width 0)
				(type default)
			)
			(fill no)
			(layer "F.CrtYd")
		)
		(fp_rect
			(start -0.508 0.9398)
			(end 0.508 -0.9398)
			(stroke
				(width 0)
				(type default)
			)
			(fill no)
			(layer "F.Fab")
		)
		(pad "1" smd custom
			(at 0 -0.4445 180)
			(size 0.1397 0.1397)
			(layers "F.Cu" "F.Mask" "F.Paste")
			(net "P12V_A")
			(options
				(clearance outline)
				(anchor circle)
			)
			(primitives
				(gr_poly
					(pts
						(arc
							(start -0.1778 -0.2794)
							(mid -0.249642 -0.249642)
							(end -0.2794 -0.1778)
						)
						(arc
							(start -0.2794 0.1778)
							(mid -0.249642 0.249642)
							(end -0.1778 0.2794)
						)
						(arc
							(start 0.1778 0.2794)
							(mid 0.249642 0.249642)
							(end 0.2794 0.1778)
						)
						(arc
							(start 0.2794 -0.1778)
							(mid 0.249642 -0.249642)
							(end 0.1778 -0.2794)
						)
					)
					(width 0)
					(fill yes)
				)
			)
		)
		(pad "2" smd custom
			(at 0 0.4445 180)
			(size 0.1397 0.1397)
			(layers "F.Cu" "F.Mask" "F.Paste")
			(net "SW_HDD_R7")
			(options
				(clearance outline)
				(anchor circle)
			)
			(primitives
				(gr_poly
					(pts
						(arc
							(start -0.1778 -0.2794)
							(mid -0.249642 -0.249642)
							(end -0.2794 -0.1778)
						)
						(arc
							(start -0.2794 0.1778)
							(mid -0.249642 0.249642)
							(end -0.1778 0.2794)
						)
						(arc
							(start 0.1778 0.2794)
							(mid 0.249642 0.249642)
							(end 0.2794 0.1778)
						)
						(arc
							(start 0.2794 -0.1778)
							(mid 0.249642 -0.249642)
							(end 0.1778 -0.2794)
						)
					)
					(width 0)
					(fill yes)
				)
			)
		)
	)
	(footprint ""
		(layer "F.Cu")
		(at 263.1186 -284.4292)
		(property "Reference" "R107"
			(at 0 0 0)
			(layer "F.SilkS")
			(hide yes)
			(effects
				(font
					(size 1.27 1.27)
				)
			)
		)
		(property "Value" "4K7R2F-GP"
			(at 0.064008 -3.993896 0)
			(unlocked yes)
			(layer "F.Fab")
			(hide yes)
			(effects
				(font
					(size 1.016 1.016)
					(thickness 0.1524)
				)
			)
		)
		(property "Device Type" "R402H16"
			(at 0.064008 -5.517896 0)
			(unlocked yes)
			(layer "F.Fab")
			(hide yes)
			(effects
				(font
					(size 1.016 1.016)
					(thickness 0.1524)
				)
			)
		)
		(duplicate_pad_numbers_are_jumpers no)
		(fp_line
			(start -0.508 -0.9398)
			(end -0.508 0.9398)
			(stroke
				(width 0.1524)
				(type default)
			)
			(layer "F.SilkS")
		)
		(fp_line
			(start 0.508 -0.9398)
			(end -0.508 -0.9398)
			(stroke
				(width 0.1524)
				(type default)
			)
			(layer "F.SilkS")
		)
		(fp_rect
			(start -0.508 0.9398)
			(end 0.508 -0.9398)
			(stroke
				(width 0)
				(type default)
			)
			(fill no)
			(layer "F.CrtYd")
		)
		(fp_rect
			(start -0.508 0.9398)
			(end 0.508 -0.9398)
			(stroke
				(width 0)
				(type default)
			)
			(fill no)
			(layer "F.Fab")
		)
		(pad "1" smd custom
			(at 0 -0.4445)
			(size 0.1397 0.1397)
			(layers "F.Cu" "F.Mask" "F.Paste")
			(net "P3V3_STBY_A")
			(options
				(clearance outline)
				(anchor circle)
			)
			(primitives
				(gr_poly
					(pts
						(arc
							(start -0.1778 -0.2794)
							(mid -0.249642 -0.249642)
							(end -0.2794 -0.1778)
						)
						(arc
							(start -0.2794 0.1778)
							(mid -0.249642 0.249642)
							(end -0.1778 0.2794)
						)
						(arc
							(start 0.1778 0.2794)
							(mid 0.249642 0.249642)
							(end 0.2794 0.1778)
						)
						(arc
							(start 0.2794 -0.1778)
							(mid 0.249642 -0.249642)
							(end 0.1778 -0.2794)
						)
					)
					(width 0)
					(fill yes)
				)
			)
		)
		(pad "2" smd custom
			(at 0 0.4445)
			(size 0.1397 0.1397)
			(layers "F.Cu" "F.Mask" "F.Paste")
			(net "IO_EXP0_HDD_FAULT_A0")
			(options
				(clearance outline)
				(anchor circle)
			)
			(primitives
				(gr_poly
					(pts
						(arc
							(start -0.1778 -0.2794)
							(mid -0.249642 -0.249642)
							(end -0.2794 -0.1778)
						)
						(arc
							(start -0.2794 0.1778)
							(mid -0.249642 0.249642)
							(end -0.1778 0.2794)
						)
						(arc
							(start 0.1778 0.2794)
							(mid 0.249642 0.249642)
							(end 0.2794 0.1778)
						)
						(arc
							(start 0.2794 -0.1778)
							(mid 0.249642 -0.249642)
							(end 0.1778 -0.2794)
						)
					)
					(width 0)
					(fill yes)
				)
			)
		)
	)
	(footprint ""
		(layer "F.Cu")
		(at 401.80895 -57.851294 90)
		(property "Reference" "C465"
			(at 0 0 90)
			(layer "F.SilkS")
			(hide yes)
			(effects
				(font
					(size 1.27 1.27)
				)
			)
		)
		(property "Value" "SCD033U25V2KX-GP"
			(at 1.1811 -2.7051 90)
			(unlocked yes)
			(layer "F.Fab")
			(hide yes)
			(effects
				(font
					(size 1.016 1.016)
					(thickness 0.1524)
				)
			)
		)
		(property "Device Type" "C402H22"
			(at 1.1811 -4.2291 90)
			(unlocked yes)
			(layer "F.Fab")
			(hide yes)
			(effects
				(font
					(size 1.016 1.016)
					(thickness 0.1524)
				)
			)
		)
		(duplicate_pad_numbers_are_jumpers no)
		(fp_rect
			(start -0.4318 0.9525)
			(end 0.4318 -0.9525)
			(stroke
				(width 0)
				(type default)
			)
			(fill no)
			(layer "F.CrtYd")
		)
		(fp_rect
			(start -0.4318 0.9525)
			(end 0.4318 -0.9525)
			(stroke
				(width 0)
				(type default)
			)
			(fill no)
			(layer "F.Fab")
		)
		(pad "1" smd custom
			(at 0 -0.4445 90)
			(size 0.1524 0.1524)
			(layers "F.Cu" "F.Mask" "F.Paste")
			(net "P12V_A")
			(options
				(clearance outline)
				(anchor circle)
			)
			(primitives
				(gr_poly
					(pts
						(arc
							(start 0.3048 -0.2032)
							(mid 0.275042 -0.275042)
							(end 0.2032 -0.3048)
						)
						(arc
							(start -0.2032 -0.3048)
							(mid -0.275042 -0.275042)
							(end -0.3048 -0.2032)
						)
						(arc
							(start -0.3048 0.2032)
							(mid -0.275042 0.275042)
							(end -0.2032 0.3048)
						)
						(arc
							(start 0.2032 0.3048)
							(mid 0.275042 0.275042)
							(end 0.3048 0.2032)
						)
					)
					(width 0)
					(fill yes)
				)
			)
		)
		(pad "2" smd custom
			(at 0 0.4445 90)
			(size 0.1524 0.1524)
			(layers "F.Cu" "F.Mask" "F.Paste")
			(net "SW_HDD_N32")
			(options
				(clearance outline)
				(anchor circle)
			)
			(primitives
				(gr_poly
					(pts
						(arc
							(start 0.3048 -0.2032)
							(mid 0.275042 -0.275042)
							(end 0.2032 -0.3048)
						)
						(arc
							(start -0.2032 -0.3048)
							(mid -0.275042 -0.275042)
							(end -0.3048 -0.2032)
						)
						(arc
							(start -0.3048 0.2032)
							(mid -0.275042 0.275042)
							(end -0.2032 0.3048)
						)
						(arc
							(start 0.2032 0.3048)
							(mid 0.275042 0.275042)
							(end 0.3048 0.2032)
						)
					)
					(width 0)
					(fill yes)
				)
			)
		)
	)
	(footprint ""
		(layer "F.Cu")
		(at 181.6862 -71.287894)
		(property "Reference" "C421"
			(at 0 0 0)
			(layer "F.SilkS")
			(hide yes)
			(effects
				(font
					(size 1.27 1.27)
				)
			)
		)
		(property "Value" "SC4D7U25V5KX-1-GP"
			(at -0.0762 -6.1214 0)
			(unlocked yes)
			(layer "F.Fab")
			(hide yes)
			(effects
				(font
					(size 1.016 1.016)
					(thickness 0.1524)
				)
			)
		)
		(property "Device Type" "C805H58"
			(at -0.0762 -8.1534 0)
			(unlocked yes)
			(layer "F.Fab")
			(hide yes)
			(effects
				(font
					(size 1.016 1.016)
					(thickness 0.1524)
				)
			)
		)
		(duplicate_pad_numbers_are_jumpers no)
		(fp_line
			(start 0.635 0)
			(end -0.635 0)
			(stroke
				(width 0.508)
				(type default)
			)
			(layer "F.SilkS")
		)
		(fp_rect
			(start -0.9652 1.778)
			(end 0.9652 -1.778)
			(stroke
				(width 0)
				(type default)
			)
			(fill no)
			(layer "F.CrtYd")
		)
		(fp_poly
			(pts
				(xy -0.9652 -1.778) (xy 0.9652 -1.778) (xy 0.9652 1.778) (xy -0.9652 1.778)
			)
			(stroke
				(width 0)
				(type default)
			)
			(fill no)
			(layer "F.Fab")
		)
		(pad "1" smd rect
			(at 0 -0.9652)
			(size 1.397 1.143)
			(layers "F.Cu" "F.Mask" "F.Paste")
			(net "P12V_HDD29")
		)
		(pad "2" smd rect
			(at 0 0.9652)
			(size 1.397 1.143)
			(layers "F.Cu" "F.Mask" "F.Paste")
			(net "GND")
		)
	)
	(footprint ""
		(layer "F.Cu")
		(at 221.742 -365.125 180)
		(property "Reference" "R151"
			(at 0 0 180)
			(layer "F.SilkS")
			(hide yes)
			(effects
				(font
					(size 1.27 1.27)
				)
			)
		)
		(property "Value" "4K7R2F-GP"
			(at 0.064008 -3.993896 180)
			(unlocked yes)
			(layer "F.Fab")
			(hide yes)
			(effects
				(font
					(size 1.016 1.016)
					(thickness 0.1524)
				)
			)
		)
		(property "Device Type" "R402H16"
			(at 0.064008 -5.517896 180)
			(unlocked yes)
			(layer "F.Fab")
			(hide yes)
			(effects
				(font
					(size 1.016 1.016)
					(thickness 0.1524)
				)
			)
		)
		(duplicate_pad_numbers_are_jumpers no)
		(fp_line
			(start 0.508 -0.9398)
			(end -0.508 -0.9398)
			(stroke
				(width 0.1524)
				(type default)
			)
			(layer "F.SilkS")
		)
		(fp_line
			(start -0.508 -0.9398)
			(end -0.508 0.9398)
			(stroke
				(width 0.1524)
				(type default)
			)
			(layer "F.SilkS")
		)
		(fp_rect
			(start -0.508 0.9398)
			(end 0.508 -0.9398)
			(stroke
				(width 0)
				(type default)
			)
			(fill no)
			(layer "F.CrtYd")
		)
		(fp_rect
			(start -0.508 0.9398)
			(end 0.508 -0.9398)
			(stroke
				(width 0)
				(type default)
			)
			(fill no)
			(layer "F.Fab")
		)
		(pad "1" smd custom
			(at 0 -0.4445 180)
			(size 0.1397 0.1397)
			(layers "F.Cu" "F.Mask" "F.Paste")
			(net "P3V3_STBY_B")
			(options
				(clearance outline)
				(anchor circle)
			)
			(primitives
				(gr_poly
					(pts
						(arc
							(start -0.1778 -0.2794)
							(mid -0.249642 -0.249642)
							(end -0.2794 -0.1778)
						)
						(arc
							(start -0.2794 0.1778)
							(mid -0.249642 0.249642)
							(end -0.1778 0.2794)
						)
						(arc
							(start 0.1778 0.2794)
							(mid 0.249642 0.249642)
							(end 0.2794 0.1778)
						)
						(arc
							(start 0.2794 -0.1778)
							(mid 0.249642 -0.249642)
							(end 0.1778 -0.2794)
						)
					)
					(width 0)
					(fill yes)
				)
			)
		)
		(pad "2" smd custom
			(at 0 0.4445 180)
			(size 0.1397 0.1397)
			(layers "F.Cu" "F.Mask" "F.Paste")
			(net "IO_EXP3_HDD_FAULT_A1")
			(options
				(clearance outline)
				(anchor circle)
			)
			(primitives
				(gr_poly
					(pts
						(arc
							(start -0.1778 -0.2794)
							(mid -0.249642 -0.249642)
							(end -0.2794 -0.1778)
						)
						(arc
							(start -0.2794 0.1778)
							(mid -0.249642 0.249642)
							(end -0.1778 0.2794)
						)
						(arc
							(start 0.1778 0.2794)
							(mid 0.249642 0.249642)
							(end 0.2794 0.1778)
						)
						(arc
							(start 0.2794 -0.1778)
							(mid 0.249642 -0.249642)
							(end 0.1778 -0.2794)
						)
					)
					(width 0)
					(fill yes)
				)
			)
		)
	)
	(footprint ""
		(layer "F.Cu")
		(at 299.390308 -24.585676 90)
		(property "Reference" "R1129"
			(at 0 0 90)
			(layer "F.SilkS")
			(hide yes)
			(effects
				(font
					(size 1.27 1.27)
				)
			)
		)
		(property "Value" "100KR2F-L1-GP"
			(at 0.064008 -3.993896 90)
			(unlocked yes)
			(layer "F.Fab")
			(hide yes)
			(effects
				(font
					(size 1.016 1.016)
					(thickness 0.1524)
				)
			)
		)
		(property "Device Type" "R402H16"
			(at 0.064008 -5.517896 90)
			(unlocked yes)
			(layer "F.Fab")
			(hide yes)
			(effects
				(font
					(size 1.016 1.016)
					(thickness 0.1524)
				)
			)
		)
		(duplicate_pad_numbers_are_jumpers no)
		(fp_line
			(start 0.508 -0.9398)
			(end -0.508 -0.9398)
			(stroke
				(width 0.1524)
				(type default)
			)
			(layer "F.SilkS")
		)
		(fp_line
			(start -0.508 -0.9398)
			(end -0.508 0.9398)
			(stroke
				(width 0.1524)
				(type default)
			)
			(layer "F.SilkS")
		)
		(fp_rect
			(start -0.508 0.9398)
			(end 0.508 -0.9398)
			(stroke
				(width 0)
				(type default)
			)
			(fill no)
			(layer "F.CrtYd")
		)
		(fp_rect
			(start -0.508 0.9398)
			(end 0.508 -0.9398)
			(stroke
				(width 0)
				(type default)
			)
			(fill no)
			(layer "F.Fab")
		)
		(pad "1" smd custom
			(at 0 -0.4445 90)
			(size 0.1397 0.1397)
			(layers "F.Cu" "F.Mask" "F.Paste")
			(net "PCIE_COMP_B_TO_IOM_B_RST_4")
			(options
				(clearance outline)
				(anchor circle)
			)
			(primitives
				(gr_poly
					(pts
						(arc
							(start -0.1778 -0.2794)
							(mid -0.249642 -0.249642)
							(end -0.2794 -0.1778)
						)
						(arc
							(start -0.2794 0.1778)
							(mid -0.249642 0.249642)
							(end -0.1778 0.2794)
						)
						(arc
							(start 0.1778 0.2794)
							(mid 0.249642 0.249642)
							(end 0.2794 0.1778)
						)
						(arc
							(start 0.2794 -0.1778)
							(mid 0.249642 -0.249642)
							(end 0.1778 -0.2794)
						)
					)
					(width 0)
					(fill yes)
				)
			)
		)
		(pad "2" smd custom
			(at 0 0.4445 90)
			(size 0.1397 0.1397)
			(layers "F.Cu" "F.Mask" "F.Paste")
			(net "GND")
			(options
				(clearance outline)
				(anchor circle)
			)
			(primitives
				(gr_poly
					(pts
						(arc
							(start -0.1778 -0.2794)
							(mid -0.249642 -0.249642)
							(end -0.2794 -0.1778)
						)
						(arc
							(start -0.2794 0.1778)
							(mid -0.249642 0.249642)
							(end -0.1778 0.2794)
						)
						(arc
							(start 0.1778 0.2794)
							(mid 0.249642 0.249642)
							(end 0.2794 0.1778)
						)
						(arc
							(start 0.2794 -0.1778)
							(mid 0.249642 -0.249642)
							(end 0.1778 -0.2794)
						)
					)
					(width 0)
					(fill yes)
				)
			)
		)
	)
	(footprint ""
		(layer "F.Cu")
		(at 449.06057 -255.199642 -90)
		(property "Reference" "R1252"
			(at 0 0 270)
			(layer "F.SilkS")
			(hide yes)
			(effects
				(font
					(size 1.27 1.27)
				)
			)
		)
		(property "Value" "15KR2F-GP"
			(at 0.064008 -3.993896 270)
			(unlocked yes)
			(layer "F.Fab")
			(hide yes)
			(effects
				(font
					(size 1.016 1.016)
					(thickness 0.1524)
				)
			)
		)
		(property "Device Type" "R402H16"
			(at 0.064008 -5.517896 270)
			(unlocked yes)
			(layer "F.Fab")
			(hide yes)
			(effects
				(font
					(size 1.016 1.016)
					(thickness 0.1524)
				)
			)
		)
		(duplicate_pad_numbers_are_jumpers no)
		(fp_line
			(start -0.508 -0.9398)
			(end -0.508 0.9398)
			(stroke
				(width 0.1524)
				(type default)
			)
			(layer "F.SilkS")
		)
		(fp_line
			(start 0.508 -0.9398)
			(end -0.508 -0.9398)
			(stroke
				(width 0.1524)
				(type default)
			)
			(layer "F.SilkS")
		)
		(fp_rect
			(start -0.508 0.9398)
			(end 0.508 -0.9398)
			(stroke
				(width 0)
				(type default)
			)
			(fill no)
			(layer "F.CrtYd")
		)
		(fp_rect
			(start -0.508 0.9398)
			(end 0.508 -0.9398)
			(stroke
				(width 0)
				(type default)
			)
			(fill no)
			(layer "F.Fab")
		)
		(pad "1" smd custom
			(at 0 -0.4445 270)
			(size 0.1397 0.1397)
			(layers "F.Cu" "F.Mask" "F.Paste")
			(net "P5V_A_3_PGOOD")
			(options
				(clearance outline)
				(anchor circle)
			)
			(primitives
				(gr_poly
					(pts
						(arc
							(start -0.1778 -0.2794)
							(mid -0.249642 -0.249642)
							(end -0.2794 -0.1778)
						)
						(arc
							(start -0.2794 0.1778)
							(mid -0.249642 0.249642)
							(end -0.1778 0.2794)
						)
						(arc
							(start 0.1778 0.2794)
							(mid 0.249642 0.249642)
							(end 0.2794 0.1778)
						)
						(arc
							(start 0.2794 -0.1778)
							(mid 0.249642 -0.249642)
							(end 0.1778 -0.2794)
						)
					)
					(width 0)
					(fill yes)
				)
			)
		)
		(pad "2" smd custom
			(at 0 0.4445 270)
			(size 0.1397 0.1397)
			(layers "F.Cu" "F.Mask" "F.Paste")
			(net "GND")
			(options
				(clearance outline)
				(anchor circle)
			)
			(primitives
				(gr_poly
					(pts
						(arc
							(start -0.1778 -0.2794)
							(mid -0.249642 -0.249642)
							(end -0.2794 -0.1778)
						)
						(arc
							(start -0.2794 0.1778)
							(mid -0.249642 0.249642)
							(end -0.1778 0.2794)
						)
						(arc
							(start 0.1778 0.2794)
							(mid 0.249642 0.249642)
							(end 0.2794 0.1778)
						)
						(arc
							(start 0.2794 -0.1778)
							(mid 0.249642 -0.249642)
							(end 0.1778 -0.2794)
						)
					)
					(width 0)
					(fill yes)
				)
			)
		)
	)
)
